(kicad_pcb
	(version 20240108)
	(generator "pcbnew")
	(generator_version "8.0")
	(general
		(thickness 1.62)
		(legacy_teardrops no)
	)
	(paper "A4")
	(title_block
		(title "Jetson Orin Baseboard")
		(date "2025-03-12")
		(rev "1.3.4")
		(company "Antmicro Ltd")
		(comment 1 "www.antmicro.com")
		(comment 9 "footprints 658-663 of 677")
	)
	(layers
		(0 "F.Cu" signal)
		(1 "In1.Cu" signal)
		(2 "In2.Cu" signal)
		(3 "In3.Cu" signal)
		(4 "In4.Cu" jumper)
		(5 "In5.Cu" signal)
		(6 "In6.Cu" signal)
		(31 "B.Cu" signal)
		(32 "B.Adhes" user "B.Adhesive")
		(33 "F.Adhes" user "F.Adhesive")
		(34 "B.Paste" user)
		(35 "F.Paste" user)
		(36 "B.SilkS" user "B.Silkscreen")
		(37 "F.SilkS" user "F.Silkscreen")
		(38 "B.Mask" user)
		(39 "F.Mask" user)
		(40 "Dwgs.User" user "User.Drawings")
		(41 "Cmts.User" user "User.Comments")
		(42 "Eco1.User" user "User.Eco1")
		(43 "Eco2.User" user "User.Eco2")
		(44 "Edge.Cuts" user)
		(45 "Margin" user)
		(46 "B.CrtYd" user "B.Courtyard")
		(47 "F.CrtYd" user "F.Courtyard")
		(48 "B.Fab" user)
		(49 "F.Fab" user)
	)
	(footprint "antmicro-footprints:R_0402_1005Metric"
		(layer "B.Cu")
		(at 142 114 180)
		(descr "Resistor SMD 0402")
		(tags "resistor SMD 0402")
		(property "Reference" "R132"
			(at -1 -1.3 0)
			(layer "B.SilkS")
			(effects
				(font
					(size 0.7 0.7)
					(thickness 0.15)
				)
				(justify left bottom mirror)
			)
		)
		(property "Value" "R_200R_0402"
			(at 0 -1.4 0)
			(layer "B.Fab")
			(effects
				(font
					(size 0.7 0.7)
					(thickness 0.15)
				)
				(justify left bottom mirror)
			)
		)
		(property "Footprint" "antmicro-footprints:R_0402_1005Metric"
			(at 0 0 180)
			(layer "F.Fab")
			(hide yes)
			(effects
				(font
					(size 1.27 1.27)
					(thickness 0.15)
				)
			)
		)
		(property "Datasheet" "https://www.bourns.com/docs/product-datasheets/cr.pdf"
			(at 0 0 180)
			(layer "F.Fab")
			(hide yes)
			(effects
				(font
					(size 1.27 1.27)
					(thickness 0.15)
				)
			)
		)
		(property "Author" "Antmicro"
			(at 284 228 0)
			(layer "B.Fab")
			(hide yes)
			(effects
				(font
					(size 1 1)
					(thickness 0.15)
				)
				(justify mirror)
			)
		)
		(property "License" "Apache-2.0"
			(at 284 228 0)
			(layer "B.Fab")
			(hide yes)
			(effects
				(font
					(size 1 1)
					(thickness 0.15)
				)
				(justify mirror)
			)
		)
		(property "MPN" "CR0402-FX-2000GLF"
			(at 284 228 0)
			(layer "B.Fab")
			(hide yes)
			(effects
				(font
					(size 1 1)
					(thickness 0.15)
				)
				(justify mirror)
			)
		)
		(property "Manufacturer" "Bourns"
			(at 284 228 0)
			(layer "B.Fab")
			(hide yes)
			(effects
				(font
					(size 1 1)
					(thickness 0.15)
				)
				(justify mirror)
			)
		)
		(property "Tolerance" "1%"
			(at 284 228 0)
			(layer "B.Fab")
			(hide yes)
			(effects
				(font
					(size 1 1)
					(thickness 0.15)
				)
				(justify mirror)
			)
		)
		(property "Val" "200R"
			(at 284 228 0)
			(layer "B.Fab")
			(hide yes)
			(effects
				(font
					(size 1 1)
					(thickness 0.15)
				)
				(justify mirror)
			)
		)
		(sheetname "CSI")
		(sheetfile "csi.kicad_sch")
		(attr smd)
		(fp_rect
			(start -0.925 0.47)
			(end 0.925 -0.47)
			(stroke
				(width 0.05)
				(type default)
			)
			(fill none)
			(layer "B.CrtYd")
		)
		(fp_rect
			(start -0.5 0.25)
			(end 0.5 -0.25)
			(stroke
				(width 0.15)
				(type solid)
			)
			(fill none)
			(layer "B.Fab")
		)
		(fp_text user "License: Apache-2.0"
			(at -0.95 -5.169 0)
			(layer "B.Fab")
			(hide yes)
			(effects
				(font
					(size 0.7 0.7)
					(thickness 0.15)
				)
				(justify left bottom mirror)
			)
		)
		(fp_text user "Author: Antmicro"
			(at -0.95 -4.169 0)
			(layer "B.Fab")
			(hide yes)
			(effects
				(font
					(size 0.7 0.7)
					(thickness 0.15)
				)
				(justify left bottom mirror)
			)
		)
		(fp_text user "${REFERENCE}"
			(at -0.95 -3.168 0)
			(layer "B.Fab")
			(hide yes)
			(effects
				(font
					(size 0.7 0.7)
					(thickness 0.15)
				)
				(justify left bottom mirror)
			)
		)
		(pad "1" smd roundrect
			(at -0.48 0 180)
			(size 0.59 0.64)
			(layers "B.Cu" "B.Paste" "B.Mask")
			(roundrect_rratio 0.25)
			(net 155 "Net-(D18-A)")
			(pintype "passive")
		)
		(pad "2" smd roundrect
			(at 0.48 0 180)
			(size 0.59 0.64)
			(layers "B.Cu" "B.Paste" "B.Mask")
			(roundrect_rratio 0.25)
			(net 108 "/CSI/CSIA_3V3")
			(pintype "passive")
		)
	)
	(footprint "antmicro-footprints:C_0402_1005Metric"
		(layer "B.Cu")
		(at 59.9 78.95)
		(descr "Capacitor SMD 0402")
		(tags "capacitor SMD 0402")
		(property "Reference" "C116"
			(at 23.11 9.2 180)
			(layer "B.SilkS")
			(effects
				(font
					(size 0.7 0.7)
					(thickness 0.15)
				)
				(justify left bottom mirror)
			)
		)
		(property "Value" "C_10u_0402"
			(at 0 -1.4 180)
			(layer "B.Fab")
			(effects
				(font
					(size 0.7 0.7)
					(thickness 0.15)
				)
				(justify left bottom mirror)
			)
		)
		(property "Footprint" "antmicro-footprints:C_0402_1005Metric"
			(at 0 0 0)
			(layer "F.Fab")
			(hide yes)
			(effects
				(font
					(size 1.27 1.27)
					(thickness 0.15)
				)
			)
		)
		(property "Datasheet" "https://www.yageo.com/en/Chart/Download/pdf/CC0402MRX5R5BB106"
			(at 0 0 0)
			(layer "F.Fab")
			(hide yes)
			(effects
				(font
					(size 1.27 1.27)
					(thickness 0.15)
				)
			)
		)
		(property "Author" "Antmicro"
			(at 0 0 0)
			(layer "B.Fab")
			(hide yes)
			(effects
				(font
					(size 1 1)
					(thickness 0.15)
				)
				(justify mirror)
			)
		)
		(property "Dielectric" ""
			(at 0 0 0)
			(layer "B.Fab")
			(hide yes)
			(effects
				(font
					(size 1 1)
					(thickness 0.15)
				)
				(justify mirror)
			)
		)
		(property "License" "Apache-2.0"
			(at 0 0 0)
			(layer "B.Fab")
			(hide yes)
			(effects
				(font
					(size 1 1)
					(thickness 0.15)
				)
				(justify mirror)
			)
		)
		(property "MPN" "CC0402MRX5R5BB106"
			(at 0 0 0)
			(layer "B.Fab")
			(hide yes)
			(effects
				(font
					(size 1 1)
					(thickness 0.15)
				)
				(justify mirror)
			)
		)
		(property "Manufacturer" "YAGEO"
			(at 0 0 0)
			(layer "B.Fab")
			(hide yes)
			(effects
				(font
					(size 1 1)
					(thickness 0.15)
				)
				(justify mirror)
			)
		)
		(property "Val" "10u"
			(at 0 0 0)
			(layer "B.Fab")
			(hide yes)
			(effects
				(font
					(size 1 1)
					(thickness 0.15)
				)
				(justify mirror)
			)
		)
		(property "Voltage" ""
			(at 0 0 0)
			(layer "B.Fab")
			(hide yes)
			(effects
				(font
					(size 1 1)
					(thickness 0.15)
				)
				(justify mirror)
			)
		)
		(sheetname "Supply")
		(sheetfile "supply.kicad_sch")
		(attr smd)
		(fp_rect
			(start -0.925 0.47)
			(end 0.925 -0.47)
			(stroke
				(width 0.05)
				(type default)
			)
			(fill none)
			(layer "B.CrtYd")
		)
		(fp_line
			(start -0.494 -0.248)
			(end 0.504 -0.248)
			(stroke
				(width 0.15)
				(type solid)
			)
			(layer "B.Fab")
		)
		(fp_line
			(start -0.494 0.25)
			(end -0.494 -0.248)
			(stroke
				(width 0.15)
				(type solid)
			)
			(layer "B.Fab")
		)
		(fp_line
			(start 0.504 -0.248)
			(end 0.504 0.25)
			(stroke
				(width 0.15)
				(type solid)
			)
			(layer "B.Fab")
		)
		(fp_line
			(start 0.504 0.25)
			(end -0.494 0.25)
			(stroke
				(width 0.15)
				(type solid)
			)
			(layer "B.Fab")
		)
		(fp_text user "License: Apache-2.0"
			(at -0.932 -5.17 180)
			(layer "B.Fab")
			(hide yes)
			(effects
				(font
					(size 0.7 0.7)
					(thickness 0.15)
				)
				(justify left bottom mirror)
			)
		)
		(fp_text user "Author: Antmicro"
			(at -0.932 -4.17 180)
			(layer "B.Fab")
			(hide yes)
			(effects
				(font
					(size 0.7 0.7)
					(thickness 0.15)
				)
				(justify left bottom mirror)
			)
		)
		(fp_text user "${REFERENCE}"
			(at -0.932 -3.168 180)
			(layer "B.Fab")
			(hide yes)
			(effects
				(font
					(size 0.7 0.7)
					(thickness 0.15)
				)
				(justify left bottom mirror)
			)
		)
		(pad "1" smd roundrect
			(at -0.48 0)
			(size 0.59 0.64)
			(layers "B.Cu" "B.Paste" "B.Mask")
			(roundrect_rratio 0.25)
			(net 1 "GND")
			(pintype "passive")
		)
		(pad "2" smd roundrect
			(at 0.48 0)
			(size 0.59 0.64)
			(layers "B.Cu" "B.Paste" "B.Mask")
			(roundrect_rratio 0.25)
			(net 137 "Net-(D36-A)")
			(pintype "passive")
		)
	)
	(footprint "antmicro-footprints:TP_SMD_0.75mm"
		(layer "B.Cu")
		(at 60 103.4 -135)
		(property "Reference" "TP25"
			(at 0 0.6 45)
			(layer "B.SilkS")
			(hide yes)
			(effects
				(font
					(size 0.7 0.7)
					(thickness 0.15)
				)
				(justify left bottom mirror)
			)
		)
		(property "Value" "TP_0.75mm_SMD"
			(at 0 -1.2 45)
			(layer "B.Fab")
			(effects
				(font
					(size 0.7 0.7)
					(thickness 0.15)
				)
				(justify left bottom mirror)
			)
		)
		(property "Footprint" "antmicro-footprints:TP_SMD_0.75mm"
			(at 0 0 -135)
			(layer "F.Fab")
			(hide yes)
			(effects
				(font
					(size 1.27 1.27)
					(thickness 0.15)
				)
			)
		)
		(property "Author" "Antmicro"
			(at 29.311566 218.941248 0)
			(layer "B.Fab")
			(hide yes)
			(effects
				(font
					(size 1 1)
					(thickness 0.15)
				)
				(justify mirror)
			)
		)
		(property "License" "Apache-2.0"
			(at 29.311566 218.941248 0)
			(layer "B.Fab")
			(hide yes)
			(effects
				(font
					(size 1 1)
					(thickness 0.15)
				)
				(justify mirror)
			)
		)
		(property "MPN" ""
			(at 29.311566 218.941248 0)
			(layer "B.Fab")
			(hide yes)
			(effects
				(font
					(size 1 1)
					(thickness 0.15)
				)
				(justify mirror)
			)
		)
		(property "Manufacturer" ""
			(at 29.311566 218.941248 0)
			(layer "B.Fab")
			(hide yes)
			(effects
				(font
					(size 1 1)
					(thickness 0.15)
				)
				(justify mirror)
			)
		)
		(sheetname "USB Debug, DP")
		(sheetfile "usb.kicad_sch")
		(attr exclude_from_pos_files exclude_from_bom)
		(fp_circle
			(center 0 0)
			(end 0.475 0)
			(stroke
				(width 0.05)
				(type default)
			)
			(fill none)
			(layer "B.CrtYd")
		)
		(fp_text user "License: Apache-2.0"
			(at -0.4 -5.101 45)
			(layer "B.Fab")
			(hide yes)
			(effects
				(font
					(size 0.7 0.7)
					(thickness 0.15)
				)
				(justify left bottom mirror)
			)
		)
		(fp_text user "${REFERENCE}"
			(at -0.4 -2.7 45)
			(layer "B.Fab")
			(hide yes)
			(effects
				(font
					(size 0.7 0.7)
					(thickness 0.15)
				)
				(justify left bottom mirror)
			)
		)
		(fp_text user "Author: Antmicro"
			(at -0.4 -3.901 45)
			(layer "B.Fab")
			(hide yes)
			(effects
				(font
					(size 0.7 0.7)
					(thickness 0.15)
				)
				(justify left bottom mirror)
			)
		)
		(pad "1" smd circle
			(at 0 0 225)
			(size 0.75 0.75)
			(layers "B.Cu" "B.Mask")
			(net 299 "/USB Debug, DP/PDC_I2C3_SDA")
			(pinfunction "1")
			(pintype "passive")
		)
	)
	(footprint "antmicro-footprints:C_0402_1005Metric"
		(layer "B.Cu")
		(at 140.01 126.6 180)
		(descr "Capacitor SMD 0402")
		(tags "capacitor SMD 0402")
		(property "Reference" "C130"
			(at -1.33 -1.33 0)
			(layer "B.SilkS")
			(effects
				(font
					(size 0.7 0.7)
					(thickness 0.15)
				)
				(justify left bottom mirror)
			)
		)
		(property "Value" "C_100n_0402"
			(at 0 -1.4 0)
			(layer "B.Fab")
			(effects
				(font
					(size 0.7 0.7)
					(thickness 0.15)
				)
				(justify left bottom mirror)
			)
		)
		(property "Footprint" "antmicro-footprints:C_0402_1005Metric"
			(at 0 0 180)
			(layer "F.Fab")
			(hide yes)
			(effects
				(font
					(size 1.27 1.27)
					(thickness 0.15)
				)
			)
		)
		(property "Datasheet" "https://www.murata.com/products/productdetail?partno=GRM155R61H104KE14%23"
			(at 0 0 180)
			(layer "F.Fab")
			(hide yes)
			(effects
				(font
					(size 1.27 1.27)
					(thickness 0.15)
				)
			)
		)
		(property "Author" "Antmicro"
			(at 280.02 253.2 0)
			(layer "B.Fab")
			(hide yes)
			(effects
				(font
					(size 1 1)
					(thickness 0.15)
				)
				(justify mirror)
			)
		)
		(property "Dielectric" "X5R"
			(at 280.02 253.2 0)
			(layer "B.Fab")
			(hide yes)
			(effects
				(font
					(size 1 1)
					(thickness 0.15)
				)
				(justify mirror)
			)
		)
		(property "License" "Apache-2.0"
			(at 280.02 253.2 0)
			(layer "B.Fab")
			(hide yes)
			(effects
				(font
					(size 1 1)
					(thickness 0.15)
				)
				(justify mirror)
			)
		)
		(property "MPN" "GRM155R61H104KE14D"
			(at 280.02 253.2 0)
			(layer "B.Fab")
			(hide yes)
			(effects
				(font
					(size 1 1)
					(thickness 0.15)
				)
				(justify mirror)
			)
		)
		(property "Manufacturer" "Murata"
			(at 280.02 253.2 0)
			(layer "B.Fab")
			(hide yes)
			(effects
				(font
					(size 1 1)
					(thickness 0.15)
				)
				(justify mirror)
			)
		)
		(property "Val" "100n"
			(at 280.02 253.2 0)
			(layer "B.Fab")
			(hide yes)
			(effects
				(font
					(size 1 1)
					(thickness 0.15)
				)
				(justify mirror)
			)
		)
		(property "Voltage" "50V"
			(at 280.02 253.2 0)
			(layer "B.Fab")
			(hide yes)
			(effects
				(font
					(size 1 1)
					(thickness 0.15)
				)
				(justify mirror)
			)
		)
		(sheetname "Peripherals")
		(sheetfile "peripherals.kicad_sch")
		(attr smd)
		(fp_rect
			(start -0.925 0.47)
			(end 0.925 -0.47)
			(stroke
				(width 0.05)
				(type default)
			)
			(fill none)
			(layer "B.CrtYd")
		)
		(fp_line
			(start 0.504 0.25)
			(end -0.494 0.25)
			(stroke
				(width 0.15)
				(type solid)
			)
			(layer "B.Fab")
		)
		(fp_line
			(start 0.504 -0.248)
			(end 0.504 0.25)
			(stroke
				(width 0.15)
				(type solid)
			)
			(layer "B.Fab")
		)
		(fp_line
			(start -0.494 0.25)
			(end -0.494 -0.248)
			(stroke
				(width 0.15)
				(type solid)
			)
			(layer "B.Fab")
		)
		(fp_line
			(start -0.494 -0.248)
			(end 0.504 -0.248)
			(stroke
				(width 0.15)
				(type solid)
			)
			(layer "B.Fab")
		)
		(fp_text user "License: Apache-2.0"
			(at -0.932 -5.17 0)
			(layer "B.Fab")
			(hide yes)
			(effects
				(font
					(size 0.7 0.7)
					(thickness 0.15)
				)
				(justify left bottom mirror)
			)
		)
		(fp_text user "${REFERENCE}"
			(at -0.932 -3.168 0)
			(layer "B.Fab")
			(hide yes)
			(effects
				(font
					(size 0.7 0.7)
					(thickness 0.15)
				)
				(justify left bottom mirror)
			)
		)
		(fp_text user "Author: Antmicro"
			(at -0.932 -4.17 0)
			(layer "B.Fab")
			(hide yes)
			(effects
				(font
					(size 0.7 0.7)
					(thickness 0.15)
				)
				(justify left bottom mirror)
			)
		)
		(pad "1" smd roundrect
			(at -0.48 0 180)
			(size 0.59 0.64)
			(layers "B.Cu" "B.Paste" "B.Mask")
			(roundrect_rratio 0.25)
			(net 87 "+3V3")
			(pintype "passive")
		)
		(pad "2" smd roundrect
			(at 0.48 0 180)
			(size 0.59 0.64)
			(layers "B.Cu" "B.Paste" "B.Mask")
			(roundrect_rratio 0.25)
			(net 1 "GND")
			(pintype "passive")
		)
	)
	(footprint "antmicro-footprints:TP_SMD_0.75mm"
		(layer "B.Cu")
		(at 68.165 120.07 180)
		(property "Reference" "TP14"
			(at -1.65 -2.2 0)
			(layer "B.SilkS")
			(hide yes)
			(effects
				(font
					(size 0.7 0.7)
					(thickness 0.15)
				)
				(justify left bottom mirror)
			)
		)
		(property "Value" "TP_0.75mm_SMD"
			(at 0 -1.2 0)
			(layer "B.Fab")
			(effects
				(font
					(size 0.7 0.7)
					(thickness 0.15)
				)
				(justify left bottom mirror)
			)
		)
		(property "Footprint" "antmicro-footprints:TP_SMD_0.75mm"
			(at 0 0 180)
			(layer "F.Fab")
			(hide yes)
			(effects
				(font
					(size 1.27 1.27)
					(thickness 0.15)
				)
			)
		)
		(property "Author" "Antmicro"
			(at 136.33 240.14 0)
			(layer "B.Fab")
			(hide yes)
			(effects
				(font
					(size 1 1)
					(thickness 0.15)
				)
				(justify mirror)
			)
		)
		(property "License" "Apache-2.0"
			(at 136.33 240.14 0)
			(layer "B.Fab")
			(hide yes)
			(effects
				(font
					(size 1 1)
					(thickness 0.15)
				)
				(justify mirror)
			)
		)
		(property "MPN" ""
			(at 136.33 240.14 0)
			(layer "B.Fab")
			(hide yes)
			(effects
				(font
					(size 1 1)
					(thickness 0.15)
				)
				(justify mirror)
			)
		)
		(property "Manufacturer" ""
			(at 136.33 240.14 0)
			(layer "B.Fab")
			(hide yes)
			(effects
				(font
					(size 1 1)
					(thickness 0.15)
				)
				(justify mirror)
			)
		)
		(sheetname "Supply")
		(sheetfile "supply.kicad_sch")
		(attr exclude_from_pos_files exclude_from_bom)
		(fp_circle
			(center 0 0)
			(end 0.475 0)
			(stroke
				(width 0.05)
				(type default)
			)
			(fill none)
			(layer "B.CrtYd")
		)
		(fp_text user "${REFERENCE}"
			(at -0.4 -2.7 0)
			(layer "B.Fab")
			(hide yes)
			(effects
				(font
					(size 0.7 0.7)
					(thickness 0.15)
				)
				(justify left bottom mirror)
			)
		)
		(fp_text user "License: Apache-2.0"
			(at -0.4 -5.101 0)
			(layer "B.Fab")
			(hide yes)
			(effects
				(font
					(size 0.7 0.7)
					(thickness 0.15)
				)
				(justify left bottom mirror)
			)
		)
		(fp_text user "Author: Antmicro"
			(at -0.4 -3.901 0)
			(layer "B.Fab")
			(hide yes)
			(effects
				(font
					(size 0.7 0.7)
					(thickness 0.15)
				)
				(justify left bottom mirror)
			)
		)
		(pad "1" smd circle
			(at 0 0 180)
			(size 0.75 0.75)
			(layers "B.Cu" "B.Mask")
			(net 115 "VCC")
			(pinfunction "1")
			(pintype "passive")
		)
	)
	(footprint "antmicro-footprints:XDFN-2_1x0.60mm"
		(layer "B.Cu")
		(at 128.95 94.5 180)
		(property "Reference" "D23"
			(at 1.1 0.55 0)
			(layer "B.SilkS")
			(effects
				(font
					(size 0.7 0.7)
					(thickness 0.15)
				)
				(justify right bottom mirror)
			)
		)
		(property "Value" "TPD1E0B04_XDFN-2"
			(at 0 -1.5 0)
			(layer "B.Fab")
			(effects
				(font
					(size 0.7 0.7)
					(thickness 0.15)
				)
				(justify left bottom mirror)
			)
		)
		(property "Footprint" "antmicro-footprints:XDFN-2_1x0.60mm"
			(at 0 0 180)
			(layer "F.Fab")
			(hide yes)
			(effects
				(font
					(size 1.27 1.27)
					(thickness 0.15)
				)
			)
		)
		(property "Datasheet" "https://www.ti.com/general/docs/suppproductinfo.tsp?distId=26&gotoUrl=https://www.ti.com/lit/gpn/tpd1e0b04"
			(at 0 0 180)
			(layer "F.Fab")
			(hide yes)
			(effects
				(font
					(size 1.27 1.27)
					(thickness 0.15)
				)
			)
		)
		(property "MPN" "TPD1E0B04DPYR"
			(at 257.9 189 0)
			(layer "B.Fab")
			(hide yes)
			(effects
				(font
					(size 1 1)
					(thickness 0.15)
				)
				(justify mirror)
			)
		)
		(property "Manufacturer" "Texas Instruments"
			(at 257.9 189 0)
			(layer "B.Fab")
			(hide yes)
			(effects
				(font
					(size 1 1)
					(thickness 0.15)
				)
				(justify mirror)
			)
		)
		(property "Author" "Antmicro"
			(at 257.9 189 0)
			(layer "B.Fab")
			(hide yes)
			(effects
				(font
					(size 1 1)
					(thickness 0.15)
				)
				(justify mirror)
			)
		)
		(property "License" "Apache-2.0"
			(at 257.9 189 0)
			(layer "B.Fab")
			(hide yes)
			(effects
				(font
					(size 1 1)
					(thickness 0.15)
				)
				(justify mirror)
			)
		)
		(sheetname "Peripherals")
		(sheetfile "peripherals.kicad_sch")
		(attr smd)
		(fp_rect
			(start -0.725 0.475)
			(end 0.725 -0.475)
			(stroke
				(width 0.05)
				(type solid)
			)
			(fill none)
			(layer "B.CrtYd")
		)
		(fp_rect
			(start -0.55 0.35)
			(end 0.55 -0.35)
			(stroke
				(width 0.15)
				(type solid)
			)
			(fill none)
			(layer "B.Fab")
		)
		(fp_text user "Author: Antmicro"
			(at -0.8 -4.4 0)
			(layer "B.Fab")
			(hide yes)
			(effects
				(font
					(size 0.7 0.7)
					(thickness 0.15)
				)
				(justify left bottom mirror)
			)
		)
		(fp_text user "License: Apache-2.0"
			(at -0.8 -5.6 0)
			(layer "B.Fab")
			(hide yes)
			(effects
				(font
					(size 0.7 0.7)
					(thickness 0.15)
				)
				(justify left bottom mirror)
			)
		)
		(fp_text user "${REFERENCE}"
			(at -0.8 -3.2 0)
			(layer "B.Fab")
			(hide yes)
			(effects
				(font
					(size 0.7 0.7)
					(thickness 0.15)
				)
				(justify left bottom mirror)
			)
		)
		(pad "1" smd roundrect
			(at -0.351 0 180)
			(size 0.3 0.5)
			(layers "B.Cu" "B.Paste" "B.Mask")
			(roundrect_rratio 0.25)
			(net 436 "USB1_D_P")
			(pinfunction "C")
			(pintype "passive")
		)
		(pad "2" smd roundrect
			(at 0.349 0 180)
			(size 0.3 0.5)
			(layers "B.Cu" "B.Paste" "B.Mask")
			(roundrect_rratio 0.25)
			(net 1 "GND")
			(pinfunction "A")
			(pintype "passive")
		)
	)
)
